FILE_TYPE = CONNECTIVITY;
{Allegro Design Entry HDL 17.4-2019 S026 (4007227) 1/17/2022}
"PAGE_NUMBER" = 178;
0"NC";
1"GND\g";
2"GND\g";
3"GND\g";
4"GND\g";
5"GND\g";
6"GND\g";
7"GND\g";
8"GND\g";
9"GND\g";
10"GND\g";
11"GND\g";
12"SW_P12V_AUX_PVDDCR_CPU1_P0_FLT\g";
13"GND\g";
14"PVDDCR_CPU1_P0_VOS5";
15"SW_PVDDCR_CPU1_P0_SW5";
16"SW_PVDDCR_CPU1_P0_BOOTR5";
17"PVDDCR_CPU1_P0_PVCC\g";
18"GND\g";
19"GND\g";
20"PVDDCR_CPU1_P0_PVCC\g";
21"GND\g";
22"PVDDCR_CPU1_P0\g";
23"GND\g";
24"GND\g";
25"SW_P12V_AUX_PVDDCR_CPU1_P0_FLT\g";
26"PVDDCR_CPU1_P0\g";
27"SW_PVDDCR_CPU1_P0_BOOT5";
28"SW_PVDDCR_CPU1_P0_BOOT5_R";
29"SW_PVDDCR_CPU1_P0_BOOT6";
30"SW_PVDDCR_CPU1_P0_BOOT6_R";
31"SW_PVDDCR_CPU1_P0_BOOTR6";
32"SW_PVDDCR_CPU1_P0_SW6";
33"IND_CPU1_P0_CPL0";
34"NC_PVDDCR_CPU1_P0_GL2_6";
35"PVDDCR_CPU1_P0_VOS6";
36"PVDDCR_CPU1_P0_VCCS"CDS_PHYS_NET_NAME"PVDDCR_CPU1_P0_VCCS";
37"IND_CPU1_P0_CPL5";
38"IND_CPU1_P0_CPL6";
39"SW_PVDDCR_CPU1_P0_SW5_RC";
40"IND_CPU1_P0_CPL6";
41"SW_PVDDCR_CPU1_P0_SW6_RC";
42"NC_PVDDCR_CPU1_P0_GL1_6";
43"NC_PVDDCR_CPU1_P0_GL2_5";
44"NC_PVDDCR_CPU1_P0_GL1_5";
45"PVDDCR_CPU1_P0_VCC5";
46"NC_PVDDCR_CPU1_P0_DNC5";
47"PVDDCR_CPU1_P0_IMON5";
48"PVDDCR_CPU1_P0_LSET5";
49"PVDDCR_CPU1_P0_VCC6";
50"NC_PVDDCR_CPU1_P0_DNC6";
51"PVDDCR_CPU1_P0_TEMP0";
52"PVDDCR_CPU1_P0_VCCS"CDS_PHYS_NET_NAME"PVDDCR_CPU1_P0_VCCS";
53"PVDDCR_CPU1_P0_IMON6";
54"PVDDCR_CPU1_P0_TEMP0";
55"PVDDCR_CPU1_P0_PWM6";
56"PVDDCR_CPU1_P0_PWM5";
57"PVDDCR_CPU1_P0_LSET6";
%"UNIVERSAL_GND"
"1","(950,1650)","0","pure_quanta_power","I1";
;
CDS_LIB"pure_quanta_power"
HDL_POWER"GND";
"A"1;
%"Q_CAP"
"1","(975,4500)","0","pure_quanta","I10";
;
LOCATION"PC132_5"
$SEC"1"
CDS_SEC"1"
PACK_TYPE"0402"
VOLTAGE"25V"
VALUE"0.1UF"
TOLERANCE"10%"
MATERIAL"X7R"
CDS_LIB"pure_quanta"
PART_NUMBER"CH4104K1B00";
"B"
$PN"2"11;
"A"
$PN"1"36;
%"Q_CAP"
"1","(1900,2650)","0","pure_quanta","I11";
;
LOCATION"PC112"
$SEC"1"
CDS_SEC"1"
PACK_TYPE"C0402"
VOLTAGE"10V"
VALUE"2.2UF"
TOLERANCE"10%"
MATERIAL"X6S"
CDS_LIB"pure_quanta"
PART_NUMBER"CH5222KEB01";
"B"
$PN"2"2;
"A"
$PN"1"49;
%"UNIVERSAL_GND"
"1","(1900,2450)","0","pure_quanta_power","I12";
;
CDS_LIB"pure_quanta_power"
HDL_POWER"GND";
"A"2;
%"Q_RES"
"2","(1900,3200)","0","pure_quanta","I13";
;
LOCATION"PR416"
$SEC"1"
CDS_SEC"1"
PACK_TYPE"0402LF"
WATTAGE"1/16W"
MATERIAL"CHIP"
TOLERANCE"1%"
VALUE"2.2"
CDS_LIB"pure_quanta"
PART_NUMBER"CS-2202FB01";
"A"
$PN"1"17;
"B"
$PN"2"49;
%"UNIVERSAL_GND"
"1","(1475,4150)","0","pure_quanta_power","I14";
;
CDS_LIB"pure_quanta_power"
HDL_POWER"GND";
"A"3;
%"Q_RES"
"2","(1475,4375)","2","pure_quanta","I15";
;
LOCATION"PR93"
$SEC"1"
CDS_SEC"1"
WATTAGE"1/16W"
MATERIAL"EMPTY"
TOLERANCE"1%"
VALUE"8.87K"
PACK_TYPE"0402LF"
CDS_LIB"pure_quanta"
PART_NUMBER"CS28872FB01";
"A"
$PN"1"48;
"B"
$PN"2"3;
%"VCC_CORE"
"1","(1900,3625)","0","pure_quanta_power","I16";
;
HDL_POWER"PVDDCR_CPU1_P0_PVCC"
CDS_LIB"pure_quanta_power";
"A"17;
%"UNIVERSAL_GND"
"1","(4025,1500)","0","pure_quanta_power","I19";
;
CDS_LIB"pure_quanta_power"
HDL_POWER"GND";
"A"18;
%"Q_CAP"
"1","(950,1850)","0","pure_quanta","I2";
;
LOCATION"PC111_6"
$SEC"1"
CDS_SEC"1"
PACK_TYPE"0402"
VOLTAGE"25V"
VALUE"0.1UF"
TOLERANCE"10%"
MATERIAL"X7R"
CDS_LIB"pure_quanta"
PART_NUMBER"CH4104K1B00";
"B"
$PN"2"1;
"A"
$PN"1"52;
%"Q_CAP"
"1","(2250,3225)","0","pure_quanta","I20";
;
LOCATION"PC113_C1P0_6"
$SEC"1"
CDS_SEC"1"
PACK_TYPE"C0402"
VALUE"2.2UF"
VOLTAGE"10V"
TOLERANCE"10%"
MATERIAL"X6S"
CDS_LIB"pure_quanta"
PART_NUMBER"CH5222KEB01";
"B"
$PN"2"4;
"A"
$PN"1"17;
%"UNIVERSAL_GND"
"1","(2250,2950)","0","pure_quanta_power","I21";
;
CDS_LIB"pure_quanta_power"
HDL_POWER"GND";
"A"4;
%"ISL99390FRZTR5935"
"1","(3400,4875)","0","pure_quanta","I22";
;
LOCATION"PU16"
$SEC"1"
CDS_SEC"1"
VALUE"ISL99390FRZ-TR5935"
MATERIAL"IC"
PART_TYPE"SMLF"
NEEDS_NO_SIZE"TRUE"
CDS_LMAN_SYM_OUTLINE"-300,700,250,-650"
CDS_LIB"pure_quanta"
PART_NUMBER"AL099390004";
"PGND2"
$PN"7_9-20_24"19;
"GL2"
$PN"41"43;
"GL1"
$PN"6"44;
"DNC"
$PN"31"46;
"EN"
$PN"35"45;
"PGND3"
$PN"40"19;
"VOS"
$PN"1"14;
"VIN2"
$PN"30"25;
"PGND1"
$PN"5"19;
"SW"
$PN"10_19"15;
"LSET"
$PN"37"48;
"IOUT"
$PN"38"47;
"TOUT_FLT"
$PN"36"54;
"PVCC"
$PN"4"20;
"PHASE"
$PN"32"16;
"VIN1"
$PN"25_29"25;
"BOOT"
$PN"33"27;
"AGND"
$PN"2"19;
"VCC"
$PN"3"45;
"REFIN"
$PN"39"36;
"PWM"
$PN"34"56;
%"UNIVERSAL_GND"
"1","(4050,4150)","0","pure_quanta_power","I23";
;
CDS_LIB"pure_quanta_power"
HDL_POWER"GND";
"A"19;
%"UNIVERSAL_GND"
"1","(1925,5100)","0","pure_quanta_power","I26";
;
CDS_LIB"pure_quanta_power"
HDL_POWER"GND";
"A"5;
%"Q_CAP"
"1","(1925,5300)","0","pure_quanta","I27";
;
LOCATION"PC131"
$SEC"1"
CDS_SEC"1"
PACK_TYPE"C0402"
VOLTAGE"10V"
VALUE"2.2UF"
TOLERANCE"10%"
MATERIAL"X6S"
CDS_LIB"pure_quanta"
PART_NUMBER"CH5222KEB01";
"B"
$PN"2"5;
"A"
$PN"1"45;
%"Q_RES"
"2","(1925,5850)","0","pure_quanta","I28";
;
LOCATION"PR94"
$SEC"1"
CDS_SEC"1"
WATTAGE"1/16W"
MATERIAL"CHIP"
TOLERANCE"1%"
VALUE"2.2"
PACK_TYPE"0402LF"
CDS_LIB"pure_quanta"
PART_NUMBER"CS-2202FB01";
"A"
$PN"1"20;
"B"
$PN"2"45;
%"VCC_CORE"
"1","(1925,6275)","0","pure_quanta_power","I29";
;
HDL_POWER"PVDDCR_CPU1_P0_PVCC"
CDS_LIB"pure_quanta_power";
"A"20;
%"UNIVERSAL_GND"
"1","(1450,1500)","0","pure_quanta_power","I3";
;
CDS_LIB"pure_quanta_power"
HDL_POWER"GND";
"A"6;
%"UNIVERSAL_GND"
"1","(2275,5600)","0","pure_quanta_power","I30";
;
CDS_LIB"pure_quanta_power"
HDL_POWER"GND";
"A"7;
%"Q_CAP"
"1","(2275,5875)","0","pure_quanta","I31";
;
LOCATION"PC133_C1P0_5"
$SEC"1"
CDS_SEC"1"
PACK_TYPE"C0402"
VOLTAGE"10V"
VALUE"2.2UF"
TOLERANCE"10%"
MATERIAL"X6S"
CDS_LIB"pure_quanta"
PART_NUMBER"CH5222KEB01";
"B"
$PN"2"7;
"A"
$PN"1"20;
%"UNIVERSAL_GND"
"1","(4800,1250)","0","pure_quanta_power","I32";
;
CDS_LIB"pure_quanta_power"
HDL_POWER"GND";
"A"8;
%"Q_RES"
"2","(4800,1475)","0","pure_quanta","I33";
;
LOCATION"PR155"
$SEC"1"
CDS_SEC"1"
MATERIAL"EMPTY"
PACK_TYPE"0402LF"
VALUE"1.5"
WATTAGE"1/8W"
TOLERANCE"1%"
CDS_LIB"pure_quanta"
PART_NUMBER"CS-1504FB00";
"A"
$PN"1"41;
"B"
$PN"2"8;
%"UNIVERSAL_GND"
"1","(5150,1875)","0","pure_quanta_power","I34";
;
CDS_LIB"pure_quanta_power"
HDL_POWER"GND";
"A"9;
%"Q_RES"
"1","(5975,1100)","0","pure_quanta","I35";
;
LOCATION"PR421"
$SEC"1"
CDS_SEC"1"
WATTAGE"1/16W"
MATERIAL"CHIP"
TOLERANCE"5%"
VALUE"0"
PACK_TYPE"0402LF"
CDS_LIB"pure_quanta"
PART_NUMBER"CS00002JB13";
"B"
$PN"2"22;
"A"
$PN"1"35;
%"Q_INDUCTOR"
"1","(5325,2000)","2","pure_quanta","I36";
;
LOCATION"PL9"
$SEC"1"
CDS_SEC"1"
VALUE"120NH/69A"
MATERIAL"IND"
PACK_TYPE"SMLF"
CDS_LIB"pure_quanta"
NEEDS_NO_SIZE"TRUE"
PART_NUMBER"CV+12^0EZ03";
"1"
$PN"1"33;
"2"
$PN"2"9;
%"Q_CAP"
"1","(5350,2450)","0","pure_quanta","I37";
;
LOCATION"PC117"
$SEC"1"
CDS_SEC"1"
PACK_TYPE"0402"
MATERIAL"X7R"
TOLERANCE"10%"
VOLTAGE"16V"
VALUE"0.22UF"
CDS_LIB"pure_quanta"
PART_NUMBER"CH4223K1B00";
"B"
$PN"2"31;
"A"
$PN"1"30;
%"Q_INDUCTOR4P_14"
"1","(6300,2100)","0","pure_quanta","I38";
;
LOCATION"PL7"
$SEC"1"
CDS_SEC"1"
PART_TYPE"SMLF"
VALUE"150NH"
MATERIAL"IND"
CDS_LIB"pure_quanta"
NEEDS_NO_SIZE"TRUE"
PART_NUMBER"CV+15^0TZ04";
"1"
$PN"1"32;
"4"
$PN"4"22;
"3"
$PN"3"40;
"2"
$PN"2"33;
%"Q_RES"
"1","(4625,2575)","0","pure_quanta","I39";
;
LOCATION"PR420"
$SEC"1"
CDS_SEC"1"
VALUE"5.6"
MATERIAL"CHIP"
WATTAGE"1/16W"
PACK_TYPE"0402LF"
TOLERANCE"1%"
CDS_LIB"pure_quanta"
PART_NUMBER"CS-5602FB01";
"B"
$PN"2"30;
"A"
$PN"1"29;
%"Q_RES"
"2","(1450,1725)","2","pure_quanta","I4";
;
LOCATION"PR7"
$SEC"1"
CDS_SEC"1"
WATTAGE"1/16W"
MATERIAL"EMPTY"
TOLERANCE"1%"
VALUE"8.87K"
PACK_TYPE"0402LF"
CDS_LIB"pure_quanta"
PART_NUMBER"CS28872FB01";
"A"
$PN"1"57;
"B"
$PN"2"6;
%"Q_CAP"
"1","(4225,3125)","0","pure_quanta","I40";
;
LOCATION"PC114_6"
$SEC"1"
CDS_SEC"1"
VOLTAGE"25V"
VALUE"0.1UF"
TOLERANCE"10%"
MATERIAL"X7R"
PACK_TYPE"0402"
CDS_LIB"pure_quanta"
PART_NUMBER"CH4104K1B00";
"B"
$PN"2"13;
"A"
$PN"1"12;
%"Q_CAP"
"1","(4650,3125)","0","pure_quanta","I41";
;
LOCATION"PC115_6"
$SEC"1"
CDS_SEC"1"
PACK_TYPE"C0402"
VOLTAGE"25V"
VALUE"1UF"
TOLERANCE"10%"
MATERIAL"X6S"
CDS_LIB"pure_quanta"
PART_NUMBER"CH5104KEB02";
"B"
$PN"2"13;
"A"
$PN"1"12;
%"Q_CAP"
"1","(5050,3125)","0","pure_quanta","I42";
;
LOCATION"PC116_6"
$SEC"1"
CDS_SEC"1"
TOLERANCE"20%"
VOLTAGE"16V"
VALUE"22UF"
PACK_TYPE"C0805"
MATERIAL"X6S"
CDS_LIB"pure_quanta"
PART_NUMBER"CH6223MEA01";
"B"
$PN"2"13;
"A"
$PN"1"12;
%"UNIVERSAL_GND"
"1","(4900,3925)","0","pure_quanta_power","I43";
;
CDS_LIB"pure_quanta_power"
HDL_POWER"GND";
"A"10;
%"Q_RES"
"2","(4900,4150)","0","pure_quanta","I44";
;
LOCATION"PR158"
$SEC"1"
CDS_SEC"1"
PACK_TYPE"0402LF"
VALUE"1.5"
TOLERANCE"1%"
MATERIAL"EMPTY"
WATTAGE"1/8W"
CDS_LIB"pure_quanta"
PART_NUMBER"CS-1504FB00";
"A"
$PN"1"39;
"B"
$PN"2"10;
%"Q_CAP"
"1","(5450,3125)","0","pure_quanta","I45";
;
LOCATION"PC118_6"
$SEC"1"
CDS_SEC"1"
TOLERANCE"20%"
VOLTAGE"16V"
VALUE"22UF"
MATERIAL"X6S"
PACK_TYPE"C0805"
CDS_LIB"pure_quanta"
PART_NUMBER"CH6223MEA01";
"B"
$PN"2"13;
"A"
$PN"1"12;
%"UNIVERSAL_GND"
"1","(5825,2775)","0","pure_quanta_power","I46";
;
CDS_LIB"pure_quanta_power"
HDL_POWER"GND";
"A"13;
%"Q_CAP"
"1","(5825,3125)","0","pure_quanta","I47";
;
LOCATION"PC119_6"
$SEC"1"
CDS_SEC"1"
TOLERANCE"20%"
VOLTAGE"16V"
VALUE"22UF"
MATERIAL"X6S"
PACK_TYPE"C0805"
CDS_LIB"pure_quanta"
PART_NUMBER"CH6223MEA01";
"B"
$PN"2"13;
"A"
$PN"1"12;
%"VCC_CORE"
"1","(5825,3475)","0","pure_quanta_power","I48";
;
HDL_POWER"SW_P12V_AUX_PVDDCR_CPU1_P0_FLT"
CDS_LIB"pure_quanta_power";
"A"12;
%"Q_RES"
"1","(6050,3800)","0","pure_quanta","I49";
;
LOCATION"PR96"
$SEC"1"
CDS_SEC"1"
TOLERANCE"5%"
VALUE"0"
PACK_TYPE"0402LF"
WATTAGE"1/16W"
MATERIAL"CHIP"
CDS_LIB"pure_quanta"
PART_NUMBER"CS00002JB13";
"B"
$PN"2"26;
"A"
$PN"1"14;
%"Q_CAP"
"1","(7675,2025)","0","pure_quanta","I51";
;
LOCATION"PC120_6"
$SEC"1"
CDS_SEC"1"
PACK_TYPE"C0805"
MATERIAL"X6S"
TOLERANCE"20%"
VALUE"22UF"
VOLTAGE"4V"
CDS_LIB"pure_quanta"
PART_NUMBER"CH622KMEA03";
"B"
$PN"2"21;
"A"
$PN"1"22;
%"UNIVERSAL_GND"
"1","(8100,1675)","0","pure_quanta_power","I52";
;
CDS_LIB"pure_quanta_power"
HDL_POWER"GND";
"A"21;
%"Q_CAP"
"1","(8100,2025)","0","pure_quanta","I53";
;
LOCATION"PC123_6"
$SEC"1"
CDS_SEC"1"
PACK_TYPE"C0805"
MATERIAL"X6S"
TOLERANCE"20%"
VALUE"22UF"
VOLTAGE"4V"
CDS_LIB"pure_quanta"
PART_NUMBER"CH622KMEA03";
"B"
$PN"2"21;
"A"
$PN"1"22;
%"VCC_CORE"
"1","(8100,2375)","0","pure_quanta_power","I54";
;
HDL_POWER"PVDDCR_CPU1_P0"
CDS_LIB"pure_quanta_power";
"A"22;
%"UNIVERSAL_GND"
"1","(8125,4325)","0","pure_quanta_power","I55";
;
CDS_LIB"pure_quanta_power"
HDL_POWER"GND";
"A"23;
%"Q_RES"
"1","(4650,5225)","0","pure_quanta","I56";
;
LOCATION"PR95"
$SEC"1"
CDS_SEC"1"
VALUE"5.6"
WATTAGE"1/16W"
PACK_TYPE"0402LF"
TOLERANCE"1%"
MATERIAL"CHIP"
CDS_LIB"pure_quanta"
PART_NUMBER"CS-5602FB01";
"B"
$PN"2"28;
"A"
$PN"1"27;
%"Q_CAP"
"1","(4900,4675)","0","pure_quanta","I57";
;
LOCATION"PC157"
$SEC"1"
CDS_SEC"1"
PACK_TYPE"C0402"
VOLTAGE"50V"
VALUE"560PF"
TOLERANCE"10%"
MATERIAL"EMPTY"
CDS_LIB"pure_quanta"
PART_NUMBER"CH1566K1B09";
"B"
$PN"2"39;
"A"
$PN"1"15;
%"Q_CAP"
"1","(4250,5775)","0","pure_quanta","I58";
;
LOCATION"PC134_5"
$SEC"1"
CDS_SEC"1"
PACK_TYPE"0402"
VOLTAGE"25V"
VALUE"0.1UF"
TOLERANCE"10%"
MATERIAL"X7R"
CDS_LIB"pure_quanta"
PART_NUMBER"CH4104K1B00";
"B"
$PN"2"24;
"A"
$PN"1"25;
%"Q_CAP"
"1","(4675,5775)","0","pure_quanta","I59";
;
LOCATION"PC135_5"
$SEC"1"
CDS_SEC"1"
PACK_TYPE"C0402"
VOLTAGE"25V"
VALUE"1UF"
TOLERANCE"10%"
MATERIAL"X6S"
CDS_LIB"pure_quanta"
PART_NUMBER"CH5104KEB02";
"B"
$PN"2"24;
"A"
$PN"1"25;
%"Q_CAP"
"1","(5075,5775)","0","pure_quanta","I60";
;
LOCATION"PC136_5"
$SEC"1"
CDS_SEC"1"
TOLERANCE"20%"
VOLTAGE"16V"
VALUE"22UF"
MATERIAL"X6S"
PACK_TYPE"C0805"
CDS_LIB"pure_quanta"
PART_NUMBER"CH6223MEA01";
"B"
$PN"2"24;
"A"
$PN"1"25;
%"Q_CAP"
"1","(5375,5100)","0","pure_quanta","I62";
;
LOCATION"PC137"
$SEC"1"
CDS_SEC"1"
VOLTAGE"16V"
VALUE"0.22UF"
PACK_TYPE"0402"
MATERIAL"X7R"
TOLERANCE"10%"
CDS_LIB"pure_quanta"
PART_NUMBER"CH4223K1B00";
"B"
$PN"2"16;
"A"
$PN"1"28;
%"Q_INDUCTOR4P_14"
"1","(6300,4750)","0","pure_quanta","I63";
;
LOCATION"PL15"
$SEC"1"
CDS_SEC"1"
PART_TYPE"SMLF"
VALUE"150NH"
MATERIAL"IND"
NEEDS_NO_SIZE"TRUE"
CDS_LIB"pure_quanta"
PART_NUMBER"CV+15^0TZ04";
"1"
$PN"1"15;
"4"
$PN"4"26;
"3"
$PN"3"37;
"2"
$PN"2"38;
%"UNIVERSAL_GND"
"1","(5850,5425)","0","pure_quanta_power","I64";
;
CDS_LIB"pure_quanta_power"
HDL_POWER"GND";
"A"24;
%"Q_CAP"
"1","(5475,5775)","0","pure_quanta","I65";
;
LOCATION"PC138_5"
$SEC"1"
CDS_SEC"1"
PACK_TYPE"C0805"
VOLTAGE"16V"
VALUE"22UF"
MATERIAL"X6S"
TOLERANCE"20%"
CDS_LIB"pure_quanta"
PART_NUMBER"CH6223MEA01";
"B"
$PN"2"24;
"A"
$PN"1"25;
%"Q_CAP"
"1","(5850,5775)","0","pure_quanta","I66";
;
LOCATION"PC139_5"
$SEC"1"
CDS_SEC"1"
VALUE"22UF"
MATERIAL"X6S"
PACK_TYPE"C0805"
VOLTAGE"16V"
TOLERANCE"20%"
CDS_LIB"pure_quanta"
PART_NUMBER"CH6223MEA01";
"B"
$PN"2"24;
"A"
$PN"1"25;
%"VCC_CORE"
"1","(5850,6125)","0","pure_quanta_power","I67";
;
HDL_POWER"SW_P12V_AUX_PVDDCR_CPU1_P0_FLT"
CDS_LIB"pure_quanta_power";
"A"25;
%"Q_CAP"
"1","(7700,4675)","0","pure_quanta","I69";
;
LOCATION"PC140_5"
$SEC"1"
CDS_SEC"1"
PACK_TYPE"C0805"
MATERIAL"X6S"
TOLERANCE"20%"
VALUE"22UF"
VOLTAGE"4V"
CDS_LIB"pure_quanta"
PART_NUMBER"CH622KMEA03";
"B"
$PN"2"23;
"A"
$PN"1"26;
%"Q_CAP"
"1","(8125,4675)","0","pure_quanta","I70";
;
LOCATION"PC141_5"
$SEC"1"
CDS_SEC"1"
PACK_TYPE"C0805"
MATERIAL"X6S"
TOLERANCE"20%"
VALUE"22UF"
VOLTAGE"4V"
CDS_LIB"pure_quanta"
PART_NUMBER"CH622KMEA03";
"B"
$PN"2"23;
"A"
$PN"1"26;
%"VCC_CORE"
"1","(8125,5025)","0","pure_quanta_power","I71";
;
HDL_POWER"PVDDCR_CPU1_P0"
CDS_LIB"pure_quanta_power";
"A"26;
%"Q_CAP"
"1","(4800,2025)","0","pure_quanta","I72";
;
LOCATION"PC154"
$SEC"1"
CDS_SEC"1"
VALUE"560PF"
VOLTAGE"50V"
TOLERANCE"10%"
MATERIAL"EMPTY"
PACK_TYPE"C0402"
CDS_LIB"pure_quanta"
PART_NUMBER"CH1566K1B09";
"B"
$PN"2"41;
"A"
$PN"1"32;
%"ISL99390FRZTR5935"
"1","(3375,2225)","0","pure_quanta","I73";
;
LOCATION"PU11"
$SEC"1"
CDS_SEC"1"
PART_TYPE"SMLF"
VALUE"ISL99390FRZ-TR5935"
MATERIAL"IC"
CDS_LIB"pure_quanta"
CDS_LMAN_SYM_OUTLINE"-300,700,250,-650"
NEEDS_NO_SIZE"TRUE"
PART_NUMBER"AL099390004";
"PGND2"
$PN"7_9-20_24"18;
"GL2"
$PN"41"34;
"GL1"
$PN"6"42;
"DNC"
$PN"31"50;
"EN"
$PN"35"49;
"PGND3"
$PN"40"18;
"VOS"
$PN"1"35;
"VIN2"
$PN"30"12;
"PGND1"
$PN"5"18;
"SW"
$PN"10_19"32;
"LSET"
$PN"37"57;
"IOUT"
$PN"38"53;
"TOUT_FLT"
$PN"36"51;
"PVCC"
$PN"4"17;
"PHASE"
$PN"32"31;
"VIN1"
$PN"25_29"12;
"BOOT"
$PN"33"29;
"AGND"
$PN"2"18;
"VCC"
$PN"3"49;
"REFIN"
$PN"39"52;
"PWM"
$PN"34"55;
%"UNIVERSAL_GND"
"1","(975,4300)","0","pure_quanta_power","I9";
;
CDS_LIB"pure_quanta_power"
HDL_POWER"GND";
"A"11;
END.
